# T6G (Grand Teton) — schematic netlist excerpt (pin names and nets, part order shuffled) for the footprints in the layout excerpt that follows; sources: Cadence DE-HDL packaged netlist, KiCad conversion of 04192023_DAF0TMB3IC0_F0TG_MB_C_brd_V02_OCP.brd

R6186  Q_RES  4.7K 5% EMPTY  pkg 0402LF  page 83 : A = FM_SEC_MUX_OE_N ; B = P3V3_AUX
C9008  Q_CAP  0.1UF 25V 10% X7R  pkg 0402  page 136 : A = P3V3_AUX ; B = GND

(kicad_pcb
	(version 20260206)
	(generator "pcbnew")
	(generator_version "10.0")
	(general
		(thickness 1.6)
		(legacy_teardrops no)
	)
	(paper "A4")
	(title_block
		(title "04192023_DAF0TMB3IC0_F0TG_MB_C_brd_V02_OCP.brd")
		(comment 1 "Grand Teton / footprints 26-27 of 8354")
	)
	(layers
		(0 "F.Cu" signal "TOP")
		(4 "In1.Cu" signal "GND")
		(6 "In2.Cu" signal "IN1")
		(8 "In3.Cu" signal "GND1")
		(10 "In4.Cu" signal "IN2")
		(12 "In5.Cu" signal "GND2")
		(14 "In6.Cu" signal "IN3")
		(16 "In7.Cu" signal "GND3")
		(18 "In8.Cu" signal "VCC")
		(20 "In9.Cu" signal "VCC1")
		(22 "In10.Cu" signal "GND4")
		(24 "In11.Cu" signal "IN4")
		(26 "In12.Cu" signal "GND5")
		(28 "In13.Cu" signal "IN5")
		(30 "In14.Cu" signal "GND6")
		(32 "In15.Cu" signal "IN6")
		(34 "In16.Cu" signal "GND7")
		(2 "B.Cu" signal "BOTTOM")
		(9 "F.Adhes" user "F.Adhesive")
		(11 "B.Adhes" user "B.Adhesive")
		(13 "F.Paste" user "Package Geometry/Pastemask Top")
		(15 "B.Paste" user "Package Geometry/Pastemask Bottom")
		(5 "F.SilkS" user "Ref Des/Silkscreen Top")
		(7 "B.SilkS" user "Ref Des/Silkscreen Bottom")
		(1 "F.Mask" user "Board Geometry/Soldermask Top")
		(3 "B.Mask" user "Board Geometry/Soldermask Bottom")
		(17 "Dwgs.User" user "User.Drawings")
		(19 "Cmts.User" user "User.Comments")
		(21 "Eco1.User" user "User.Eco1")
		(23 "Eco2.User" user "User.Eco2")
		(25 "Edge.Cuts" user "Board Geometry/Outline")
		(27 "Margin" user)
		(31 "F.CrtYd" user "Package Geometry/Place Bound Top")
		(29 "B.CrtYd" user "Package Geometry/Place Bound Bottom")
		(35 "F.Fab" user "Ref Des/Assembly Top")
		(33 "B.Fab" user "Ref Des/Assembly Bottom")
	)
	(footprint ""
		(layer "F.Cu")
		(at 218.567 -100.457)
		(property "Reference" "C9008"
			(at 0 0 0)
			(layer "F.SilkS")
			(hide yes)
			(effects
				(font
					(size 1.27 1.27)
				)
			)
		)
		(property "Value" ""
			(at 0 0 0)
			(layer "F.Fab")
			(effects
				(font
					(size 1.27 1.27)
				)
			)
		)
		(duplicate_pad_numbers_are_jumpers no)
		(fp_line
			(start -0.7874 -0.4064)
			(end 0.7874 -0.4064)
			(stroke
				(width 0.1524)
				(type default)
			)
			(layer "F.SilkS")
		)
		(fp_line
			(start -0.7874 0.4064)
			(end -0.7874 -0.4064)
			(stroke
				(width 0.1524)
				(type default)
			)
			(layer "F.SilkS")
		)
		(fp_line
			(start 0.7874 -0.4064)
			(end 0.7874 0.4064)
			(stroke
				(width 0.1524)
				(type default)
			)
			(layer "F.SilkS")
		)
		(fp_line
			(start 0.7874 0.4064)
			(end -0.7874 0.4064)
			(stroke
				(width 0.1524)
				(type default)
			)
			(layer "F.SilkS")
		)
		(fp_line
			(start -0.67945 -0.305054)
			(end -0.12065 -0.305054)
			(stroke
				(width 0.1)
				(type default)
			)
			(layer "F.Fab")
		)
		(fp_line
			(start -0.67945 0.3048)
			(end -0.67945 -0.305054)
			(stroke
				(width 0.1)
				(type default)
			)
			(layer "F.Fab")
		)
		(fp_line
			(start -0.12065 -0.305054)
			(end -0.12065 -0.2794)
			(stroke
				(width 0.1)
				(type default)
			)
			(layer "F.Fab")
		)
		(fp_line
			(start -0.12065 -0.2794)
			(end 0.12065 -0.2794)
			(stroke
				(width 0.1)
				(type default)
			)
			(layer "F.Fab")
		)
		(fp_line
			(start -0.12065 0.2794)
			(end -0.12065 0.3048)
			(stroke
				(width 0.1)
				(type default)
			)
			(layer "F.Fab")
		)
		(fp_line
			(start -0.12065 0.3048)
			(end -0.67945 0.3048)
			(stroke
				(width 0.1)
				(type default)
			)
			(layer "F.Fab")
		)
		(fp_line
			(start 0.120396 0.2794)
			(end -0.12065 0.2794)
			(stroke
				(width 0.1)
				(type default)
			)
			(layer "F.Fab")
		)
		(fp_line
			(start 0.120396 0.3048)
			(end 0.120396 0.2794)
			(stroke
				(width 0.1)
				(type default)
			)
			(layer "F.Fab")
		)
		(fp_line
			(start 0.12065 -0.3048)
			(end 0.67945 -0.3048)
			(stroke
				(width 0.1)
				(type default)
			)
			(layer "F.Fab")
		)
		(fp_line
			(start 0.12065 -0.2794)
			(end 0.12065 -0.3048)
			(stroke
				(width 0.1)
				(type default)
			)
			(layer "F.Fab")
		)
		(fp_line
			(start 0.67945 -0.3048)
			(end 0.67945 0.3048)
			(stroke
				(width 0.1)
				(type default)
			)
			(layer "F.Fab")
		)
		(fp_line
			(start 0.67945 0.3048)
			(end 0.120396 0.3048)
			(stroke
				(width 0.1)
				(type default)
			)
			(layer "F.Fab")
		)
		(pad "1" smd circle
			(at -0.40005 0)
			(size 0 0)
			(layers "F.Cu" "F.Mask" "F.Paste")
			(net "P3V3_AUX")
		)
		(pad "2" smd circle
			(at 0.40005 0)
			(size 0 0)
			(layers "F.Cu" "F.Mask" "F.Paste")
			(net "GND")
		)
	)
	(footprint ""
		(layer "F.Cu")
		(at 163.582096 -102.984046 180)
		(property "Reference" "R6186"
			(at 0 0 180)
			(layer "F.SilkS")
			(hide yes)
			(effects
				(font
					(size 1.27 1.27)
				)
			)
		)
		(property "Value" ""
			(at 0 0 180)
			(layer "F.Fab")
			(effects
				(font
					(size 1.27 1.27)
				)
			)
		)
		(duplicate_pad_numbers_are_jumpers no)
		(fp_line
			(start 0.7874 0.4064)
			(end -0.7874 0.4064)
			(stroke
				(width 0.1524)
				(type default)
			)
			(layer "F.SilkS")
		)
		(fp_line
			(start 0.7874 -0.4064)
			(end 0.7874 0.4064)
			(stroke
				(width 0.1524)
				(type default)
			)
			(layer "F.SilkS")
		)
		(fp_line
			(start -0.7874 0.4064)
			(end -0.7874 -0.4064)
			(stroke
				(width 0.1524)
				(type default)
			)
			(layer "F.SilkS")
		)
		(fp_line
			(start -0.7874 -0.4064)
			(end 0.7874 -0.4064)
			(stroke
				(width 0.1524)
				(type default)
			)
			(layer "F.SilkS")
		)
		(fp_line
			(start 0.67945 0.3048)
			(end 0.120396 0.3048)
			(stroke
				(width 0.1)
				(type default)
			)
			(layer "F.Fab")
		)
		(fp_line
			(start 0.67945 -0.3048)
			(end 0.67945 0.3048)
			(stroke
				(width 0.1)
				(type default)
			)
			(layer "F.Fab")
		)
		(fp_line
			(start 0.12065 -0.2794)
			(end 0.12065 -0.3048)
			(stroke
				(width 0.1)
				(type default)
			)
			(layer "F.Fab")
		)
		(fp_line
			(start 0.12065 -0.3048)
			(end 0.67945 -0.3048)
			(stroke
				(width 0.1)
				(type default)
			)
			(layer "F.Fab")
		)
		(fp_line
			(start 0.120396 0.3048)
			(end 0.120396 0.2794)
			(stroke
				(width 0.1)
				(type default)
			)
			(layer "F.Fab")
		)
		(fp_line
			(start 0.120396 0.2794)
			(end -0.12065 0.2794)
			(stroke
				(width 0.1)
				(type default)
			)
			(layer "F.Fab")
		)
		(fp_line
			(start -0.12065 0.3048)
			(end -0.67945 0.3048)
			(stroke
				(width 0.1)
				(type default)
			)
			(layer "F.Fab")
		)
		(fp_line
			(start -0.12065 0.2794)
			(end -0.12065 0.3048)
			(stroke
				(width 0.1)
				(type default)
			)
			(layer "F.Fab")
		)
		(fp_line
			(start -0.12065 -0.2794)
			(end 0.12065 -0.2794)
			(stroke
				(width 0.1)
				(type default)
			)
			(layer "F.Fab")
		)
		(fp_line
			(start -0.12065 -0.305054)
			(end -0.12065 -0.2794)
			(stroke
				(width 0.1)
				(type default)
			)
			(layer "F.Fab")
		)
		(fp_line
			(start -0.67945 0.3048)
			(end -0.67945 -0.305054)
			(stroke
				(width 0.1)
				(type default)
			)
			(layer "F.Fab")
		)
		(fp_line
			(start -0.67945 -0.305054)
			(end -0.12065 -0.305054)
			(stroke
				(width 0.1)
				(type default)
			)
			(layer "F.Fab")
		)
		(pad "1" smd circle
			(at -0.40005 0 180)
			(size 0 0)
			(layers "F.Cu" "F.Mask" "F.Paste")
			(net "FM_SEC_MUX_OE_N")
		)
		(pad "2" smd circle
			(at 0.40005 0 180)
			(size 0 0)
			(layers "F.Cu" "F.Mask" "F.Paste")
			(net "P3V3_AUX")
		)
	)
)
